(kicad_pcb
	(version 20241229)
	(generator "pcbnew")
	(generator_version "9.0")
	(general
		(thickness 1.63)
		(legacy_teardrops no)
	)
	(paper "A4")
	(title_block
		(title "CM4 Baseboard")
		(date "2026-01-05")
		(rev "1.1.1")
		(company "Antmicro Ltd")
		(comment 1 "www.antmicro.com")
		(comment 9 "footprints 134-136 of 506")
	)
	(layers
		(0 "F.Cu" signal)
		(4 "In1.Cu" power)
		(6 "In2.Cu" power)
		(8 "In3.Cu" signal)
		(10 "In4.Cu" signal)
		(2 "B.Cu" signal)
		(9 "F.Adhes" user "F.Adhesive")
		(11 "B.Adhes" user "B.Adhesive")
		(13 "F.Paste" user)
		(15 "B.Paste" user)
		(5 "F.SilkS" user "F.Silkscreen")
		(7 "B.SilkS" user "B.Silkscreen")
		(1 "F.Mask" user)
		(3 "B.Mask" user)
		(17 "Dwgs.User" user "User.Drawings")
		(19 "Cmts.User" user "User.Comments")
		(21 "Eco1.User" user "User.Eco1")
		(23 "Eco2.User" user "User.Eco2")
		(25 "Edge.Cuts" user)
		(27 "Margin" user)
		(31 "F.CrtYd" user "F.Courtyard")
		(29 "B.CrtYd" user "B.Courtyard")
		(35 "F.Fab" user)
		(33 "B.Fab" user)
	)
	(footprint "antmicro-footprints:C_0402_1005Metric"
		(layer "F.Cu")
		(at 95.867962 142.7165)
		(descr "Capacitor SMD 0402")
		(tags "capacitor SMD 0402")
		(property "Reference" "C933"
			(at 0.5 -0.4 0)
			(layer "F.SilkS")
			(effects
				(font
					(size 0.7 0.7)
					(thickness 0.15)
				)
				(justify left bottom)
			)
		)
		(property "Value" "C_100n_0402"
			(at -1.022927 2.155213 0)
			(layer "F.Fab")
			(effects
				(font
					(size 0.7 0.7)
					(thickness 0.15)
				)
				(justify left bottom)
			)
		)
		(property "Datasheet" "https://www.murata.com/products/productdetail?partno=GRM155R61H104KE14%23"
			(at 0 0 0)
			(layer "F.Fab")
			(hide yes)
			(effects
				(font
					(size 1.27 1.27)
					(thickness 0.15)
				)
			)
		)
		(property "MPN" "GRM155R61H104KE14D"
			(at 0 0 0)
			(unlocked yes)
			(layer "F.Fab")
			(hide yes)
			(effects
				(font
					(size 1 1)
					(thickness 0.15)
				)
			)
		)
		(property "Manufacturer" "Murata"
			(at 0 0 0)
			(unlocked yes)
			(layer "F.Fab")
			(hide yes)
			(effects
				(font
					(size 1 1)
					(thickness 0.15)
				)
			)
		)
		(property "License" "Apache-2.0"
			(at 0 0 0)
			(unlocked yes)
			(layer "F.Fab")
			(hide yes)
			(effects
				(font
					(size 1 1)
					(thickness 0.15)
				)
			)
		)
		(property "Author" "Antmicro"
			(at 0 0 0)
			(unlocked yes)
			(layer "F.Fab")
			(hide yes)
			(effects
				(font
					(size 1 1)
					(thickness 0.15)
				)
			)
		)
		(property "Val" "100n"
			(at 0 0 0)
			(unlocked yes)
			(layer "F.Fab")
			(hide yes)
			(effects
				(font
					(size 1 1)
					(thickness 0.15)
				)
			)
		)
		(property "Voltage" "50V"
			(at 0 0 0)
			(unlocked yes)
			(layer "F.Fab")
			(hide yes)
			(effects
				(font
					(size 1 1)
					(thickness 0.15)
				)
			)
		)
		(property "Dielectric" "X5R"
			(at 0 0 0)
			(unlocked yes)
			(layer "F.Fab")
			(hide yes)
			(effects
				(font
					(size 1 1)
					(thickness 0.15)
				)
			)
		)
		(sheetname "/USB/")
		(sheetfile "usb.kicad_sch")
		(attr smd)
		(fp_rect
			(start -0.925 -0.47)
			(end 0.925 0.47)
			(stroke
				(width 0.05)
				(type default)
			)
			(fill no)
			(layer "F.CrtYd")
		)
		(fp_line
			(start -0.494 -0.25)
			(end 0.504 -0.25)
			(stroke
				(width 0.15)
				(type solid)
			)
			(layer "F.Fab")
		)
		(fp_line
			(start -0.494 0.248)
			(end -0.494 -0.25)
			(stroke
				(width 0.15)
				(type solid)
			)
			(layer "F.Fab")
		)
		(fp_line
			(start 0.504 -0.25)
			(end 0.504 0.248)
			(stroke
				(width 0.15)
				(type solid)
			)
			(layer "F.Fab")
		)
		(fp_line
			(start 0.504 0.248)
			(end -0.494 0.248)
			(stroke
				(width 0.15)
				(type solid)
			)
			(layer "F.Fab")
		)
		(fp_text user "Author: Antmicro"
			(at -0.939 3.399 0)
			(layer "F.Fab")
			(effects
				(font
					(size 0.7 0.7)
					(thickness 0.15)
				)
				(justify left bottom)
			)
		)
		(fp_text user "${REFERENCE}"
			(at -0.939 4.599 0)
			(layer "F.Fab")
			(effects
				(font
					(size 0.7 0.7)
					(thickness 0.15)
				)
				(justify left bottom)
			)
		)
		(fp_text user "License: Apache-2.0"
			(at -0.939 5.799 0)
			(layer "F.Fab")
			(effects
				(font
					(size 0.7 0.7)
					(thickness 0.15)
				)
				(justify left bottom)
			)
		)
		(pad "1" smd roundrect
			(at -0.48 0)
			(size 0.59 0.64)
			(layers "F.Cu" "F.Mask" "F.Paste")
			(roundrect_rratio 0.25)
			(net 3 "GND")
			(pintype "passive")
		)
		(pad "2" smd roundrect
			(at 0.48 0)
			(size 0.59 0.64)
			(layers "F.Cu" "F.Mask" "F.Paste")
			(roundrect_rratio 0.25)
			(net 27 "/USB/USB_3V3")
			(pintype "passive")
		)
	)
	(footprint "antmicro-footprints:Nexperia_DFN-10_2.5x1mm_P0.5mm"
		(layer "F.Cu")
		(at 142.292962 144.3915 90)
		(property "Reference" "D803"
			(at 4.365 1.175 90)
			(layer "F.SilkS")
			(effects
				(font
					(size 0.7 0.7)
					(thickness 0.15)
				)
				(justify left bottom)
			)
		)
		(property "Value" "PUSB3F96X_PASS"
			(at -0.016 1.705 90)
			(layer "F.Fab")
			(effects
				(font
					(size 0.7 0.7)
					(thickness 0.15)
				)
				(justify left bottom)
			)
		)
		(property "Datasheet" "https://mouser.com/datasheet/2/916/PUSB3F96-1600324.pdf"
			(at 0 0 90)
			(layer "F.Fab")
			(hide yes)
			(effects
				(font
					(size 1.27 1.27)
					(thickness 0.15)
				)
			)
		)
		(property "Manufacturer" "Nexperia"
			(at 0 0 90)
			(unlocked yes)
			(layer "F.Fab")
			(hide yes)
			(effects
				(font
					(size 1 1)
					(thickness 0.15)
				)
			)
		)
		(property "MPN" "PUSB3F96X"
			(at 0 0 90)
			(unlocked yes)
			(layer "F.Fab")
			(hide yes)
			(effects
				(font
					(size 1 1)
					(thickness 0.15)
				)
			)
		)
		(property "Author" "Antmicro"
			(at 0 0 90)
			(unlocked yes)
			(layer "F.Fab")
			(hide yes)
			(effects
				(font
					(size 1 1)
					(thickness 0.15)
				)
			)
		)
		(property "License" "Apache-2.0"
			(at 0 0 90)
			(unlocked yes)
			(layer "F.Fab")
			(hide yes)
			(effects
				(font
					(size 1 1)
					(thickness 0.15)
				)
			)
		)
		(sheetname "/Peripherals/")
		(sheetfile "peripherals.kicad_sch")
		(attr smd)
		(fp_line
			(start -1.375 -0.4)
			(end -1.375 0.4)
			(stroke
				(width 0.15)
				(type solid)
			)
			(layer "F.SilkS")
		)
		(fp_line
			(start 1.375 0.4)
			(end 1.375 -0.4)
			(stroke
				(width 0.15)
				(type solid)
			)
			(layer "F.SilkS")
		)
		(fp_circle
			(center -1.4 0.7)
			(end -1.349 0.7)
			(stroke
				(width 0.15)
				(type solid)
			)
			(fill yes)
			(layer "F.SilkS")
		)
		(fp_rect
			(start -1.4 -0.725)
			(end 1.4 0.725)
			(stroke
				(width 0.05)
				(type solid)
			)
			(fill no)
			(layer "F.CrtYd")
		)
		(fp_line
			(start 1.25 -0.5)
			(end -1.25 -0.5)
			(stroke
				(width 0.15)
				(type solid)
			)
			(layer "F.Fab")
		)
		(fp_line
			(start -1.25 -0.5)
			(end -1.25 0.15)
			(stroke
				(width 0.15)
				(type solid)
			)
			(layer "F.Fab")
		)
		(fp_line
			(start -1.25 0.15)
			(end -0.9 0.5)
			(stroke
				(width 0.15)
				(type solid)
			)
			(layer "F.Fab")
		)
		(fp_line
			(start 1.25 0.5)
			(end 1.25 -0.5)
			(stroke
				(width 0.15)
				(type solid)
			)
			(layer "F.Fab")
		)
		(fp_line
			(start -0.9 0.5)
			(end 1.25 0.5)
			(stroke
				(width 0.15)
				(type solid)
			)
			(layer "F.Fab")
		)
		(fp_text user "${REFERENCE}"
			(at -1.367 3.704 90)
			(layer "F.Fab")
			(effects
				(font
					(size 0.7 0.7)
					(thickness 0.15)
				)
				(justify left bottom)
			)
		)
		(fp_text user "Author: Antmicro"
			(at -1.367 4.905 90)
			(layer "F.Fab")
			(effects
				(font
					(size 0.7 0.7)
					(thickness 0.15)
				)
				(justify left bottom)
			)
		)
		(fp_text user "License: Apache-2.0"
			(at -1.367 6.105 90)
			(layer "F.Fab")
			(effects
				(font
					(size 0.7 0.7)
					(thickness 0.15)
				)
				(justify left bottom)
			)
		)
		(pad "1" smd rect
			(at -1 0.3875 90)
			(size 0.2 0.475)
			(layers "F.Cu" "F.Mask" "F.Paste")
			(net 229 "/Compute module/GPIO.9{slash}RXD4")
			(pinfunction "CH1")
			(pintype "passive")
			(solder_mask_margin 0.05)
		)
		(pad "2" smd rect
			(at -0.5 0.3875 90)
			(size 0.2 0.475)
			(layers "F.Cu" "F.Mask" "F.Paste")
			(net 227 "/Compute module/GPIO.11")
			(pinfunction "CH2")
			(pintype "passive")
			(solder_mask_margin 0.05)
		)
		(pad "3" smd rect
			(at 0 0.3875 90)
			(size 0.2 0.475)
			(layers "F.Cu" "F.Mask" "F.Paste")
			(net 3 "GND")
			(pinfunction "GND")
			(pintype "passive")
			(solder_mask_margin 0.05)
		)
		(pad "4" smd rect
			(at 0.5 0.3875 90)
			(size 0.2 0.475)
			(layers "F.Cu" "F.Mask" "F.Paste")
			(net 447 "/Compute module/GPIO.0{slash}SDA0")
			(pinfunction "CH3")
			(pintype "passive")
			(solder_mask_margin 0.05)
		)
		(pad "5" smd rect
			(at 1 0.3875 90)
			(size 0.2 0.475)
			(layers "F.Cu" "F.Mask" "F.Paste")
			(net 225 "/Compute module/GPIO.5{slash}RXD3")
			(pinfunction "CH4")
			(pintype "passive")
			(solder_mask_margin 0.05)
		)
		(pad "6" smd rect
			(at 1 -0.3875 90)
			(size 0.2 0.475)
			(layers "F.Cu" "F.Mask" "F.Paste")
			(net 225 "/Compute module/GPIO.5{slash}RXD3")
			(pinfunction "CH4")
			(pintype "passive")
			(solder_mask_margin 0.05)
		)
		(pad "7" smd rect
			(at 0.5 -0.3875 90)
			(size 0.2 0.475)
			(layers "F.Cu" "F.Mask" "F.Paste")
			(net 447 "/Compute module/GPIO.0{slash}SDA0")
			(pinfunction "CH3")
			(pintype "passive")
			(solder_mask_margin 0.05)
		)
		(pad "8" smd rect
			(at 0 -0.3875 90)
			(size 0.2 0.475)
			(layers "F.Cu" "F.Mask" "F.Paste")
			(net 3 "GND")
			(pinfunction "GND")
			(pintype "passive")
			(solder_mask_margin 0.05)
		)
		(pad "9" smd rect
			(at -0.501 -0.3875 90)
			(size 0.2 0.475)
			(layers "F.Cu" "F.Mask" "F.Paste")
			(net 227 "/Compute module/GPIO.11")
			(pinfunction "CH2")
			(pintype "passive")
			(solder_mask_margin 0.05)
		)
		(pad "10" smd rect
			(at -1 -0.3875 90)
			(size 0.2 0.475)
			(layers "F.Cu" "F.Mask" "F.Paste")
			(net 229 "/Compute module/GPIO.9{slash}RXD4")
			(pinfunction "CH1")
			(pintype "passive")
			(solder_mask_margin 0.05)
		)
	)
	(footprint "antmicro-footprints:R_0402_1005Metric"
		(layer "F.Cu")
		(at 57.342962 134.3665 90)
		(descr "Resistor SMD 0402")
		(tags "resistor SMD 0402")
		(property "Reference" "R414"
			(at -1.985 3.495 90)
			(layer "F.SilkS")
			(effects
				(font
					(size 0.7 0.7)
					(thickness 0.15)
				)
				(justify left bottom)
			)
		)
		(property "Value" "R_24k9_0402"
			(at -1.011843 1.772047 90)
			(layer "F.Fab")
			(effects
				(font
					(size 0.7 0.7)
					(thickness 0.15)
				)
				(justify left bottom)
			)
		)
		(property "Datasheet" "https://www.bourns.com/docs/product-datasheets/cr.pdf"
			(at 0 0 90)
			(layer "F.Fab")
			(hide yes)
			(effects
				(font
					(size 1.27 1.27)
					(thickness 0.15)
				)
			)
		)
		(property "Manufacturer" "Bourns"
			(at 0 0 90)
			(unlocked yes)
			(layer "F.Fab")
			(hide yes)
			(effects
				(font
					(size 1 1)
					(thickness 0.15)
				)
			)
		)
		(property "MPN" "CR0402-FX-2492GLF"
			(at 0 0 90)
			(unlocked yes)
			(layer "F.Fab")
			(hide yes)
			(effects
				(font
					(size 1 1)
					(thickness 0.15)
				)
			)
		)
		(property "Val" "24k9"
			(at 0 0 90)
			(unlocked yes)
			(layer "F.Fab")
			(hide yes)
			(effects
				(font
					(size 1 1)
					(thickness 0.15)
				)
			)
		)
		(property "License" "Apache-2.0"
			(at 0 0 90)
			(unlocked yes)
			(layer "F.Fab")
			(hide yes)
			(effects
				(font
					(size 1 1)
					(thickness 0.15)
				)
			)
		)
		(property "Author" "Antmicro"
			(at 0 0 90)
			(unlocked yes)
			(layer "F.Fab")
			(hide yes)
			(effects
				(font
					(size 1 1)
					(thickness 0.15)
				)
			)
		)
		(property "Tolerance" "1%"
			(at 0 0 90)
			(unlocked yes)
			(layer "F.Fab")
			(hide yes)
			(effects
				(font
					(size 1 1)
					(thickness 0.15)
				)
			)
		)
		(sheetname "/Ethernet/")
		(sheetfile "ethernet.kicad_sch")
		(attr smd)
		(fp_rect
			(start -0.925 -0.47)
			(end 0.925 0.47)
			(stroke
				(width 0.05)
				(type default)
			)
			(fill no)
			(layer "F.CrtYd")
		)
		(fp_rect
			(start -0.5 -0.25)
			(end 0.5 0.25)
			(stroke
				(width 0.15)
				(type solid)
			)
			(fill no)
			(layer "F.Fab")
		)
		(fp_text user "${REFERENCE}"
			(at -0.95 3.168 90)
			(layer "F.Fab")
			(effects
				(font
					(size 0.7 0.7)
					(thickness 0.15)
				)
				(justify left bottom)
			)
		)
		(fp_text user "License: Apache-2.0"
			(at -0.95 5.169 90)
			(layer "F.Fab")
			(effects
				(font
					(size 0.7 0.7)
					(thickness 0.15)
				)
				(justify left bottom)
			)
		)
		(fp_text user "Author: Antmicro"
			(at -0.95 4.169 90)
			(layer "F.Fab")
			(effects
				(font
					(size 0.7 0.7)
					(thickness 0.15)
				)
				(justify left bottom)
			)
		)
		(pad "1" smd roundrect
			(at -0.48 0 90)
			(size 0.59 0.64)
			(layers "F.Cu" "F.Mask" "F.Paste")
			(roundrect_rratio 0.25)
			(net 477 "Net-(D404-A)")
			(pintype "passive")
		)
		(pad "2" smd roundrect
			(at 0.48 0 90)
			(size 0.59 0.64)
			(layers "F.Cu" "F.Mask" "F.Paste")
			(roundrect_rratio 0.25)
			(net 33 "/Ethernet/VDD")
			(pintype "passive")
		)
	)
)
